# T6G (Grand Teton) — schematic netlist excerpt (pin names and nets, part order shuffled) for the footprints in the layout excerpt that follows; sources: Cadence DE-HDL packaged netlist, KiCad conversion of 04192023_DAF0TMB3IC0_F0TG_MB_C_brd_V02_OCP.brd

R3304  Q_RES  0 5% CHIP  pkg 0402LF  page 143 : A = OCP_SFF_PRSNT_ALL_R_N ; B = OCP_SFF_PRSNT_ALL_R3_N
R1208  Q_RES  470 1% CHIP  pkg 0402LF  page 166 : A = PU_P12V_ALL_PWROK_LED ; B = P5V_AUX

(kicad_pcb
	(version 20260206)
	(generator "pcbnew")
	(generator_version "10.0")
	(general
		(thickness 1.6)
		(legacy_teardrops no)
	)
	(paper "A4")
	(title_block
		(title "04192023_DAF0TMB3IC0_F0TG_MB_C_brd_V02_OCP.brd")
		(comment 1 "Grand Teton / footprints 1493-1494 of 8354")
	)
	(layers
		(0 "F.Cu" signal "TOP")
		(4 "In1.Cu" signal "GND")
		(6 "In2.Cu" signal "IN1")
		(8 "In3.Cu" signal "GND1")
		(10 "In4.Cu" signal "IN2")
		(12 "In5.Cu" signal "GND2")
		(14 "In6.Cu" signal "IN3")
		(16 "In7.Cu" signal "GND3")
		(18 "In8.Cu" signal "VCC")
		(20 "In9.Cu" signal "VCC1")
		(22 "In10.Cu" signal "GND4")
		(24 "In11.Cu" signal "IN4")
		(26 "In12.Cu" signal "GND5")
		(28 "In13.Cu" signal "IN5")
		(30 "In14.Cu" signal "GND6")
		(32 "In15.Cu" signal "IN6")
		(34 "In16.Cu" signal "GND7")
		(2 "B.Cu" signal "BOTTOM")
		(9 "F.Adhes" user "F.Adhesive")
		(11 "B.Adhes" user "B.Adhesive")
		(13 "F.Paste" user "Package Geometry/Pastemask Top")
		(15 "B.Paste" user "Package Geometry/Pastemask Bottom")
		(5 "F.SilkS" user "Ref Des/Silkscreen Top")
		(7 "B.SilkS" user "Ref Des/Silkscreen Bottom")
		(1 "F.Mask" user "Board Geometry/Soldermask Top")
		(3 "B.Mask" user "Board Geometry/Soldermask Bottom")
		(17 "Dwgs.User" user "User.Drawings")
		(19 "Cmts.User" user "User.Comments")
		(21 "Eco1.User" user "User.Eco1")
		(23 "Eco2.User" user "User.Eco2")
		(25 "Edge.Cuts" user "Board Geometry/Outline")
		(27 "Margin" user)
		(31 "F.CrtYd" user "Package Geometry/Place Bound Top")
		(29 "B.CrtYd" user "Package Geometry/Place Bound Bottom")
		(35 "F.Fab" user "Ref Des/Assembly Top")
		(33 "B.Fab" user "Ref Des/Assembly Bottom")
	)
	(footprint ""
		(layer "F.Cu")
		(at 347.4593 -15.979394 90)
		(property "Reference" "R1208"
			(at 0 0 90)
			(layer "F.SilkS")
			(hide yes)
			(effects
				(font
					(size 1.27 1.27)
				)
			)
		)
		(property "Value" ""
			(at 0 0 90)
			(layer "F.Fab")
			(effects
				(font
					(size 1.27 1.27)
				)
			)
		)
		(duplicate_pad_numbers_are_jumpers no)
		(fp_line
			(start 0.7874 -0.4064)
			(end 0.7874 0.4064)
			(stroke
				(width 0.1524)
				(type default)
			)
			(layer "F.SilkS")
		)
		(fp_line
			(start -0.7874 -0.4064)
			(end 0.7874 -0.4064)
			(stroke
				(width 0.1524)
				(type default)
			)
			(layer "F.SilkS")
		)
		(fp_line
			(start 0.7874 0.4064)
			(end -0.7874 0.4064)
			(stroke
				(width 0.1524)
				(type default)
			)
			(layer "F.SilkS")
		)
		(fp_line
			(start -0.7874 0.4064)
			(end -0.7874 -0.4064)
			(stroke
				(width 0.1524)
				(type default)
			)
			(layer "F.SilkS")
		)
		(fp_line
			(start -0.12065 -0.305054)
			(end -0.12065 -0.2794)
			(stroke
				(width 0.1)
				(type default)
			)
			(layer "F.Fab")
		)
		(fp_line
			(start -0.67945 -0.305054)
			(end -0.12065 -0.305054)
			(stroke
				(width 0.1)
				(type default)
			)
			(layer "F.Fab")
		)
		(fp_line
			(start 0.67945 -0.3048)
			(end 0.67945 0.3048)
			(stroke
				(width 0.1)
				(type default)
			)
			(layer "F.Fab")
		)
		(fp_line
			(start 0.12065 -0.3048)
			(end 0.67945 -0.3048)
			(stroke
				(width 0.1)
				(type default)
			)
			(layer "F.Fab")
		)
		(fp_line
			(start 0.12065 -0.2794)
			(end 0.12065 -0.3048)
			(stroke
				(width 0.1)
				(type default)
			)
			(layer "F.Fab")
		)
		(fp_line
			(start -0.12065 -0.2794)
			(end 0.12065 -0.2794)
			(stroke
				(width 0.1)
				(type default)
			)
			(layer "F.Fab")
		)
		(fp_line
			(start 0.120396 0.2794)
			(end -0.12065 0.2794)
			(stroke
				(width 0.1)
				(type default)
			)
			(layer "F.Fab")
		)
		(fp_line
			(start -0.12065 0.2794)
			(end -0.12065 0.3048)
			(stroke
				(width 0.1)
				(type default)
			)
			(layer "F.Fab")
		)
		(fp_line
			(start 0.67945 0.3048)
			(end 0.120396 0.3048)
			(stroke
				(width 0.1)
				(type default)
			)
			(layer "F.Fab")
		)
		(fp_line
			(start 0.120396 0.3048)
			(end 0.120396 0.2794)
			(stroke
				(width 0.1)
				(type default)
			)
			(layer "F.Fab")
		)
		(fp_line
			(start -0.12065 0.3048)
			(end -0.67945 0.3048)
			(stroke
				(width 0.1)
				(type default)
			)
			(layer "F.Fab")
		)
		(fp_line
			(start -0.67945 0.3048)
			(end -0.67945 -0.305054)
			(stroke
				(width 0.1)
				(type default)
			)
			(layer "F.Fab")
		)
		(pad "1" smd circle
			(at -0.40005 0 90)
			(size 0 0)
			(layers "F.Cu" "F.Mask" "F.Paste")
			(net "PU_P12V_ALL_PWROK_LED")
		)
		(pad "2" smd circle
			(at 0.40005 0 90)
			(size 0 0)
			(layers "F.Cu" "F.Mask" "F.Paste")
			(net "P5V_AUX")
		)
	)
	(footprint ""
		(layer "F.Cu")
		(at 157.88259 -95.517208 90)
		(property "Reference" "R3304"
			(at 0 0 90)
			(layer "F.SilkS")
			(hide yes)
			(effects
				(font
					(size 1.27 1.27)
				)
			)
		)
		(property "Value" ""
			(at 0 0 90)
			(layer "F.Fab")
			(effects
				(font
					(size 1.27 1.27)
				)
			)
		)
		(duplicate_pad_numbers_are_jumpers no)
		(fp_line
			(start 0.7874 -0.4064)
			(end 0.7874 0.4064)
			(stroke
				(width 0.1524)
				(type default)
			)
			(layer "F.SilkS")
		)
		(fp_line
			(start -0.7874 -0.4064)
			(end 0.7874 -0.4064)
			(stroke
				(width 0.1524)
				(type default)
			)
			(layer "F.SilkS")
		)
		(fp_line
			(start 0.7874 0.4064)
			(end -0.7874 0.4064)
			(stroke
				(width 0.1524)
				(type default)
			)
			(layer "F.SilkS")
		)
		(fp_line
			(start -0.7874 0.4064)
			(end -0.7874 -0.4064)
			(stroke
				(width 0.1524)
				(type default)
			)
			(layer "F.SilkS")
		)
		(fp_line
			(start -0.12065 -0.305054)
			(end -0.12065 -0.2794)
			(stroke
				(width 0.1)
				(type default)
			)
			(layer "F.Fab")
		)
		(fp_line
			(start -0.67945 -0.305054)
			(end -0.12065 -0.305054)
			(stroke
				(width 0.1)
				(type default)
			)
			(layer "F.Fab")
		)
		(fp_line
			(start 0.67945 -0.3048)
			(end 0.67945 0.3048)
			(stroke
				(width 0.1)
				(type default)
			)
			(layer "F.Fab")
		)
		(fp_line
			(start 0.12065 -0.3048)
			(end 0.67945 -0.3048)
			(stroke
				(width 0.1)
				(type default)
			)
			(layer "F.Fab")
		)
		(fp_line
			(start 0.12065 -0.2794)
			(end 0.12065 -0.3048)
			(stroke
				(width 0.1)
				(type default)
			)
			(layer "F.Fab")
		)
		(fp_line
			(start -0.12065 -0.2794)
			(end 0.12065 -0.2794)
			(stroke
				(width 0.1)
				(type default)
			)
			(layer "F.Fab")
		)
		(fp_line
			(start 0.120396 0.2794)
			(end -0.12065 0.2794)
			(stroke
				(width 0.1)
				(type default)
			)
			(layer "F.Fab")
		)
		(fp_line
			(start -0.12065 0.2794)
			(end -0.12065 0.3048)
			(stroke
				(width 0.1)
				(type default)
			)
			(layer "F.Fab")
		)
		(fp_line
			(start 0.67945 0.3048)
			(end 0.120396 0.3048)
			(stroke
				(width 0.1)
				(type default)
			)
			(layer "F.Fab")
		)
		(fp_line
			(start 0.120396 0.3048)
			(end 0.120396 0.2794)
			(stroke
				(width 0.1)
				(type default)
			)
			(layer "F.Fab")
		)
		(fp_line
			(start -0.12065 0.3048)
			(end -0.67945 0.3048)
			(stroke
				(width 0.1)
				(type default)
			)
			(layer "F.Fab")
		)
		(fp_line
			(start -0.67945 0.3048)
			(end -0.67945 -0.305054)
			(stroke
				(width 0.1)
				(type default)
			)
			(layer "F.Fab")
		)
		(pad "1" smd circle
			(at -0.40005 0 90)
			(size 0 0)
			(layers "F.Cu" "F.Mask" "F.Paste")
			(net "OCP_SFF_PRSNT_ALL_R_N")
		)
		(pad "2" smd circle
			(at 0.40005 0 90)
			(size 0 0)
			(layers "F.Cu" "F.Mask" "F.Paste")
			(net "OCP_SFF_PRSNT_ALL_R3_N")
		)
	)
)
